# T6G (Grand Teton) — schematic netlist excerpt (pin names and nets, part order shuffled) for the footprints in the layout excerpt that follows; sources: Cadence DE-HDL packaged netlist, KiCad conversion of 04192023_DAF0TMB3IC0_F0TG_MB_C_brd_V02_OCP.brd

C378  Q_CAP  0.1UF 10V 10% X7S  pkg C0201  page 345 : A = P1V8_CPU1_RT2_1A_1D ; B = GND
C88  Q_CAP  0.1UF 25V 10% X7R  pkg 0402  page 86 : A = P3V3_AUX ; B = GND

(kicad_pcb
	(version 20260206)
	(generator "pcbnew")
	(generator_version "10.0")
	(general
		(thickness 1.6)
		(legacy_teardrops no)
	)
	(paper "A4")
	(title_block
		(title "04192023_DAF0TMB3IC0_F0TG_MB_C_brd_V02_OCP.brd")
		(comment 1 "Grand Teton / footprints 7000-7001 of 8354")
	)
	(layers
		(0 "F.Cu" signal "TOP")
		(4 "In1.Cu" signal "GND")
		(6 "In2.Cu" signal "IN1")
		(8 "In3.Cu" signal "GND1")
		(10 "In4.Cu" signal "IN2")
		(12 "In5.Cu" signal "GND2")
		(14 "In6.Cu" signal "IN3")
		(16 "In7.Cu" signal "GND3")
		(18 "In8.Cu" signal "VCC")
		(20 "In9.Cu" signal "VCC1")
		(22 "In10.Cu" signal "GND4")
		(24 "In11.Cu" signal "IN4")
		(26 "In12.Cu" signal "GND5")
		(28 "In13.Cu" signal "IN5")
		(30 "In14.Cu" signal "GND6")
		(32 "In15.Cu" signal "IN6")
		(34 "In16.Cu" signal "GND7")
		(2 "B.Cu" signal "BOTTOM")
		(9 "F.Adhes" user "F.Adhesive")
		(11 "B.Adhes" user "B.Adhesive")
		(13 "F.Paste" user "Package Geometry/Pastemask Top")
		(15 "B.Paste" user "Package Geometry/Pastemask Bottom")
		(5 "F.SilkS" user "Ref Des/Silkscreen Top")
		(7 "B.SilkS" user "Ref Des/Silkscreen Bottom")
		(1 "F.Mask" user "Board Geometry/Soldermask Top")
		(3 "B.Mask" user "Board Geometry/Soldermask Bottom")
		(17 "Dwgs.User" user "User.Drawings")
		(19 "Cmts.User" user "User.Comments")
		(21 "Eco1.User" user "User.Eco1")
		(23 "Eco2.User" user "User.Eco2")
		(25 "Edge.Cuts" user "Board Geometry/Outline")
		(27 "Margin" user)
		(31 "F.CrtYd" user "Package Geometry/Place Bound Top")
		(29 "B.CrtYd" user "Package Geometry/Place Bound Bottom")
		(35 "F.Fab" user "Ref Des/Assembly Top")
		(33 "B.Fab" user "Ref Des/Assembly Bottom")
	)
	(footprint ""
		(layer "B.Cu")
		(at 157.94609 -388.011162 -90)
		(property "Reference" "C378"
			(at 0 0 90)
			(layer "B.SilkS")
			(hide yes)
			(effects
				(font
					(size 1.27 1.27)
				)
				(justify mirror)
			)
		)
		(property "Value" ""
			(at 0 0 90)
			(layer "B.Fab")
			(effects
				(font
					(size 1.27 1.27)
				)
				(justify mirror)
			)
		)
		(duplicate_pad_numbers_are_jumpers no)
		(fp_line
			(start -0.299974 0.150114)
			(end 0.299974 0.150114)
			(stroke
				(width 0.1)
				(type default)
			)
			(layer "B.Fab")
		)
		(fp_line
			(start 0.299974 0.150114)
			(end 0.299974 -0.150114)
			(stroke
				(width 0.1)
				(type default)
			)
			(layer "B.Fab")
		)
		(fp_line
			(start -0.299974 -0.150114)
			(end -0.299974 0.150114)
			(stroke
				(width 0.1)
				(type default)
			)
			(layer "B.Fab")
		)
		(fp_line
			(start 0.299974 -0.150114)
			(end -0.299974 -0.150114)
			(stroke
				(width 0.1)
				(type default)
			)
			(layer "B.Fab")
		)
		(pad "1" smd rect
			(at 0.2667 0 90)
			(size 0.3048 0.381)
			(layers "B.Cu" "B.Mask" "B.Paste")
			(net "P1V8_CPU1_RT2_1A_1D")
		)
		(pad "2" smd rect
			(at -0.2667 0 90)
			(size 0.3048 0.381)
			(layers "B.Cu" "B.Mask" "B.Paste")
			(net "GND")
		)
	)
	(footprint ""
		(layer "B.Cu")
		(at 307.34127 -193.99631)
		(property "Reference" "C88"
			(at 0 0 0)
			(layer "B.SilkS")
			(hide yes)
			(effects
				(font
					(size 1.27 1.27)
				)
				(justify mirror)
			)
		)
		(property "Value" ""
			(at 0 0 0)
			(layer "B.Fab")
			(effects
				(font
					(size 1.27 1.27)
				)
				(justify mirror)
			)
		)
		(duplicate_pad_numbers_are_jumpers no)
		(fp_line
			(start -0.7874 -0.4064)
			(end -0.7874 0.4064)
			(stroke
				(width 0.1524)
				(type default)
			)
			(layer "B.SilkS")
		)
		(fp_line
			(start -0.7874 0.4064)
			(end 0.7874 0.4064)
			(stroke
				(width 0.1524)
				(type default)
			)
			(layer "B.SilkS")
		)
		(fp_line
			(start 0.7874 -0.4064)
			(end -0.7874 -0.4064)
			(stroke
				(width 0.1524)
				(type default)
			)
			(layer "B.SilkS")
		)
		(fp_line
			(start 0.7874 0.4064)
			(end 0.7874 -0.4064)
			(stroke
				(width 0.1524)
				(type default)
			)
			(layer "B.SilkS")
		)
		(fp_line
			(start -0.67945 -0.3048)
			(end -0.67945 0.3048)
			(stroke
				(width 0.1)
				(type default)
			)
			(layer "B.Fab")
		)
		(fp_line
			(start -0.67945 0.3048)
			(end -0.120396 0.3048)
			(stroke
				(width 0.1)
				(type default)
			)
			(layer "B.Fab")
		)
		(fp_line
			(start -0.12065 -0.3048)
			(end -0.67945 -0.3048)
			(stroke
				(width 0.1)
				(type default)
			)
			(layer "B.Fab")
		)
		(fp_line
			(start -0.12065 -0.2794)
			(end -0.12065 -0.3048)
			(stroke
				(width 0.1)
				(type default)
			)
			(layer "B.Fab")
		)
		(fp_line
			(start -0.120396 0.2794)
			(end 0.12065 0.2794)
			(stroke
				(width 0.1)
				(type default)
			)
			(layer "B.Fab")
		)
		(fp_line
			(start -0.120396 0.3048)
			(end -0.120396 0.2794)
			(stroke
				(width 0.1)
				(type default)
			)
			(layer "B.Fab")
		)
		(fp_line
			(start 0.12065 -0.305054)
			(end 0.12065 -0.2794)
			(stroke
				(width 0.1)
				(type default)
			)
			(layer "B.Fab")
		)
		(fp_line
			(start 0.12065 -0.2794)
			(end -0.12065 -0.2794)
			(stroke
				(width 0.1)
				(type default)
			)
			(layer "B.Fab")
		)
		(fp_line
			(start 0.12065 0.2794)
			(end 0.12065 0.3048)
			(stroke
				(width 0.1)
				(type default)
			)
			(layer "B.Fab")
		)
		(fp_line
			(start 0.12065 0.3048)
			(end 0.67945 0.3048)
			(stroke
				(width 0.1)
				(type default)
			)
			(layer "B.Fab")
		)
		(fp_line
			(start 0.67945 -0.305054)
			(end 0.12065 -0.305054)
			(stroke
				(width 0.1)
				(type default)
			)
			(layer "B.Fab")
		)
		(fp_line
			(start 0.67945 0.3048)
			(end 0.67945 -0.305054)
			(stroke
				(width 0.1)
				(type default)
			)
			(layer "B.Fab")
		)
		(pad "1" smd circle
			(at 0.40005 0 180)
			(size 0 0)
			(layers "B.Cu" "B.Mask" "B.Paste")
			(net "P3V3_AUX")
		)
		(pad "2" smd circle
			(at -0.40005 0 180)
			(size 0 0)
			(layers "B.Cu" "B.Mask" "B.Paste")
			(net "GND")
		)
	)
)
